(kicad_pcb
	(version 20260206)
	(generator "pcbnew")
	(generator_version "10.0")
	(general
		(thickness 1.6)
		(legacy_teardrops no)
	)
	(paper "A4")
	(title_block
		(title "9054_F0T_PDB_BD_GPU_F_V04_1213_1550_OCP.brd")
		(comment 1 "Grand Teton / footprints 197-203 of 608")
	)
	(layers
		(0 "F.Cu" signal "TOP")
		(4 "In1.Cu" signal "GND")
		(6 "In2.Cu" signal "IN1")
		(8 "In3.Cu" signal "GND1")
		(10 "In4.Cu" signal "VCC")
		(12 "In5.Cu" signal "VCC1")
		(14 "In6.Cu" signal "GND2")
		(16 "In7.Cu" signal "IN2")
		(18 "In8.Cu" signal "GND3")
		(2 "B.Cu" signal "BOTTOM")
		(9 "F.Adhes" user "F.Adhesive")
		(11 "B.Adhes" user "B.Adhesive")
		(13 "F.Paste" user "Package Geometry/Pastemask Top")
		(15 "B.Paste" user "Package Geometry/Pastemask Bottom")
		(5 "F.SilkS" user "Ref Des/Silkscreen Top")
		(7 "B.SilkS" user "Ref Des/Silkscreen Bottom")
		(1 "F.Mask" user "Board Geometry/Soldermask Top")
		(3 "B.Mask" user "Board Geometry/Soldermask Bottom")
		(17 "Dwgs.User" user "User.Drawings")
		(19 "Cmts.User" user "User.Comments")
		(21 "Eco1.User" user "User.Eco1")
		(23 "Eco2.User" user "User.Eco2")
		(25 "Edge.Cuts" user "Board Geometry/Outline")
		(27 "Margin" user)
		(31 "F.CrtYd" user "Package Geometry/Place Bound Top")
		(29 "B.CrtYd" user "Package Geometry/Place Bound Bottom")
		(35 "F.Fab" user "Ref Des/Assembly Top")
		(33 "B.Fab" user "Ref Des/Assembly Bottom")
	)
	(footprint ""
		(layer "F.Cu")
		(at 449.326 -26.543)
		(property "Reference" "R16"
			(at 0 0 0)
			(layer "F.SilkS")
			(hide yes)
			(effects
				(font
					(size 1.27 1.27)
				)
			)
		)
		(property "Value" ""
			(at 0 0 0)
			(layer "F.Fab")
			(effects
				(font
					(size 1.27 1.27)
				)
			)
		)
		(duplicate_pad_numbers_are_jumpers no)
		(fp_line
			(start -0.7874 -0.4064)
			(end 0.7874 -0.4064)
			(stroke
				(width 0.1524)
				(type default)
			)
			(layer "F.SilkS")
		)
		(fp_line
			(start -0.7874 0.4064)
			(end -0.7874 -0.4064)
			(stroke
				(width 0.1524)
				(type default)
			)
			(layer "F.SilkS")
		)
		(fp_line
			(start 0.7874 -0.4064)
			(end 0.7874 0.4064)
			(stroke
				(width 0.1524)
				(type default)
			)
			(layer "F.SilkS")
		)
		(fp_line
			(start 0.7874 0.4064)
			(end -0.7874 0.4064)
			(stroke
				(width 0.1524)
				(type default)
			)
			(layer "F.SilkS")
		)
		(fp_line
			(start -0.67945 -0.305054)
			(end -0.12065 -0.305054)
			(stroke
				(width 0.1)
				(type default)
			)
			(layer "F.Fab")
		)
		(fp_line
			(start -0.67945 0.3048)
			(end -0.67945 -0.305054)
			(stroke
				(width 0.1)
				(type default)
			)
			(layer "F.Fab")
		)
		(fp_line
			(start -0.12065 -0.305054)
			(end -0.12065 -0.2794)
			(stroke
				(width 0.1)
				(type default)
			)
			(layer "F.Fab")
		)
		(fp_line
			(start -0.12065 -0.2794)
			(end 0.12065 -0.2794)
			(stroke
				(width 0.1)
				(type default)
			)
			(layer "F.Fab")
		)
		(fp_line
			(start -0.12065 0.2794)
			(end -0.12065 0.3048)
			(stroke
				(width 0.1)
				(type default)
			)
			(layer "F.Fab")
		)
		(fp_line
			(start -0.12065 0.3048)
			(end -0.67945 0.3048)
			(stroke
				(width 0.1)
				(type default)
			)
			(layer "F.Fab")
		)
		(fp_line
			(start 0.120396 0.2794)
			(end -0.12065 0.2794)
			(stroke
				(width 0.1)
				(type default)
			)
			(layer "F.Fab")
		)
		(fp_line
			(start 0.120396 0.3048)
			(end 0.120396 0.2794)
			(stroke
				(width 0.1)
				(type default)
			)
			(layer "F.Fab")
		)
		(fp_line
			(start 0.12065 -0.3048)
			(end 0.67945 -0.3048)
			(stroke
				(width 0.1)
				(type default)
			)
			(layer "F.Fab")
		)
		(fp_line
			(start 0.12065 -0.2794)
			(end 0.12065 -0.3048)
			(stroke
				(width 0.1)
				(type default)
			)
			(layer "F.Fab")
		)
		(fp_line
			(start 0.67945 -0.3048)
			(end 0.67945 0.3048)
			(stroke
				(width 0.1)
				(type default)
			)
			(layer "F.Fab")
		)
		(fp_line
			(start 0.67945 0.3048)
			(end 0.120396 0.3048)
			(stroke
				(width 0.1)
				(type default)
			)
			(layer "F.Fab")
		)
		(pad "1" smd circle
			(at -0.40005 0)
			(size 0 0)
			(layers "F.Cu" "F.Mask" "F.Paste")
			(net "PU_9543_1_FAN")
		)
		(pad "2" smd circle
			(at 0.40005 0)
			(size 0 0)
			(layers "F.Cu" "F.Mask" "F.Paste")
			(net "P3V3_AUX")
		)
	)
	(footprint ""
		(layer "F.Cu")
		(at 451.057264 -85.870796 -90)
		(property "Reference" "PR112"
			(at 0 0 270)
			(layer "F.SilkS")
			(hide yes)
			(effects
				(font
					(size 1.27 1.27)
				)
			)
		)
		(property "Value" ""
			(at 0 0 270)
			(layer "F.Fab")
			(effects
				(font
					(size 1.27 1.27)
				)
			)
		)
		(duplicate_pad_numbers_are_jumpers no)
		(fp_line
			(start -0.7874 0.4064)
			(end -0.7874 -0.4064)
			(stroke
				(width 0.1524)
				(type default)
			)
			(layer "F.SilkS")
		)
		(fp_line
			(start 0.7874 0.4064)
			(end -0.7874 0.4064)
			(stroke
				(width 0.1524)
				(type default)
			)
			(layer "F.SilkS")
		)
		(fp_line
			(start -0.7874 -0.4064)
			(end 0.7874 -0.4064)
			(stroke
				(width 0.1524)
				(type default)
			)
			(layer "F.SilkS")
		)
		(fp_line
			(start 0.7874 -0.4064)
			(end 0.7874 0.4064)
			(stroke
				(width 0.1524)
				(type default)
			)
			(layer "F.SilkS")
		)
		(fp_line
			(start -0.67945 0.3048)
			(end -0.67945 -0.305054)
			(stroke
				(width 0.1)
				(type default)
			)
			(layer "F.Fab")
		)
		(fp_line
			(start -0.12065 0.3048)
			(end -0.67945 0.3048)
			(stroke
				(width 0.1)
				(type default)
			)
			(layer "F.Fab")
		)
		(fp_line
			(start 0.120396 0.3048)
			(end 0.120396 0.2794)
			(stroke
				(width 0.1)
				(type default)
			)
			(layer "F.Fab")
		)
		(fp_line
			(start 0.67945 0.3048)
			(end 0.120396 0.3048)
			(stroke
				(width 0.1)
				(type default)
			)
			(layer "F.Fab")
		)
		(fp_line
			(start -0.12065 0.2794)
			(end -0.12065 0.3048)
			(stroke
				(width 0.1)
				(type default)
			)
			(layer "F.Fab")
		)
		(fp_line
			(start 0.120396 0.2794)
			(end -0.12065 0.2794)
			(stroke
				(width 0.1)
				(type default)
			)
			(layer "F.Fab")
		)
		(fp_line
			(start -0.12065 -0.2794)
			(end 0.12065 -0.2794)
			(stroke
				(width 0.1)
				(type default)
			)
			(layer "F.Fab")
		)
		(fp_line
			(start 0.12065 -0.2794)
			(end 0.12065 -0.3048)
			(stroke
				(width 0.1)
				(type default)
			)
			(layer "F.Fab")
		)
		(fp_line
			(start 0.12065 -0.3048)
			(end 0.67945 -0.3048)
			(stroke
				(width 0.1)
				(type default)
			)
			(layer "F.Fab")
		)
		(fp_line
			(start 0.67945 -0.3048)
			(end 0.67945 0.3048)
			(stroke
				(width 0.1)
				(type default)
			)
			(layer "F.Fab")
		)
		(fp_line
			(start -0.67945 -0.305054)
			(end -0.12065 -0.305054)
			(stroke
				(width 0.1)
				(type default)
			)
			(layer "F.Fab")
		)
		(fp_line
			(start -0.12065 -0.305054)
			(end -0.12065 -0.2794)
			(stroke
				(width 0.1)
				(type default)
			)
			(layer "F.Fab")
		)
		(pad "1" smd circle
			(at -0.40005 0 270)
			(size 0 0)
			(layers "F.Cu" "F.Mask" "F.Paste")
			(net "P3V3_HPDB_FB")
		)
		(pad "2" smd circle
			(at 0.40005 0 270)
			(size 0 0)
			(layers "F.Cu" "F.Mask" "F.Paste")
			(net "P3V3_AUX")
		)
	)
	(footprint ""
		(layer "F.Cu")
		(at 448.056 -37.211 90)
		(property "Reference" "R14"
			(at 0 0 90)
			(layer "F.SilkS")
			(hide yes)
			(effects
				(font
					(size 1.27 1.27)
				)
			)
		)
		(property "Value" ""
			(at 0 0 90)
			(layer "F.Fab")
			(effects
				(font
					(size 1.27 1.27)
				)
			)
		)
		(duplicate_pad_numbers_are_jumpers no)
		(fp_line
			(start 0.7874 -0.4064)
			(end 0.7874 0.4064)
			(stroke
				(width 0.1524)
				(type default)
			)
			(layer "F.SilkS")
		)
		(fp_line
			(start -0.7874 -0.4064)
			(end 0.7874 -0.4064)
			(stroke
				(width 0.1524)
				(type default)
			)
			(layer "F.SilkS")
		)
		(fp_line
			(start 0.7874 0.4064)
			(end -0.7874 0.4064)
			(stroke
				(width 0.1524)
				(type default)
			)
			(layer "F.SilkS")
		)
		(fp_line
			(start -0.7874 0.4064)
			(end -0.7874 -0.4064)
			(stroke
				(width 0.1524)
				(type default)
			)
			(layer "F.SilkS")
		)
		(fp_line
			(start -0.12065 -0.305054)
			(end -0.12065 -0.2794)
			(stroke
				(width 0.1)
				(type default)
			)
			(layer "F.Fab")
		)
		(fp_line
			(start -0.67945 -0.305054)
			(end -0.12065 -0.305054)
			(stroke
				(width 0.1)
				(type default)
			)
			(layer "F.Fab")
		)
		(fp_line
			(start 0.67945 -0.3048)
			(end 0.67945 0.3048)
			(stroke
				(width 0.1)
				(type default)
			)
			(layer "F.Fab")
		)
		(fp_line
			(start 0.12065 -0.3048)
			(end 0.67945 -0.3048)
			(stroke
				(width 0.1)
				(type default)
			)
			(layer "F.Fab")
		)
		(fp_line
			(start 0.12065 -0.2794)
			(end 0.12065 -0.3048)
			(stroke
				(width 0.1)
				(type default)
			)
			(layer "F.Fab")
		)
		(fp_line
			(start -0.12065 -0.2794)
			(end 0.12065 -0.2794)
			(stroke
				(width 0.1)
				(type default)
			)
			(layer "F.Fab")
		)
		(fp_line
			(start 0.120396 0.2794)
			(end -0.12065 0.2794)
			(stroke
				(width 0.1)
				(type default)
			)
			(layer "F.Fab")
		)
		(fp_line
			(start -0.12065 0.2794)
			(end -0.12065 0.3048)
			(stroke
				(width 0.1)
				(type default)
			)
			(layer "F.Fab")
		)
		(fp_line
			(start 0.67945 0.3048)
			(end 0.120396 0.3048)
			(stroke
				(width 0.1)
				(type default)
			)
			(layer "F.Fab")
		)
		(fp_line
			(start 0.120396 0.3048)
			(end 0.120396 0.2794)
			(stroke
				(width 0.1)
				(type default)
			)
			(layer "F.Fab")
		)
		(fp_line
			(start -0.12065 0.3048)
			(end -0.67945 0.3048)
			(stroke
				(width 0.1)
				(type default)
			)
			(layer "F.Fab")
		)
		(fp_line
			(start -0.67945 0.3048)
			(end -0.67945 -0.305054)
			(stroke
				(width 0.1)
				(type default)
			)
			(layer "F.Fab")
		)
		(pad "1" smd circle
			(at -0.40005 0 90)
			(size 0 0)
			(layers "F.Cu" "F.Mask" "F.Paste")
			(net "SMB_P52V_SDA")
		)
		(pad "2" smd circle
			(at 0.40005 0 90)
			(size 0 0)
			(layers "F.Cu" "F.Mask" "F.Paste")
			(net "SMB_P52V_PDB_SDA_R")
		)
	)
	(footprint ""
		(layer "F.Cu")
		(at 397.637 -78.74)
		(property "Reference" "PC41"
			(at -8.6106 -4.79933 0)
			(unlocked yes)
			(layer "F.SilkS")
			(effects
				(font
					(size 0.7874 0.5842)
					(thickness 0.1524)
				)
				(justify left)
			)
		)
		(property "Value" ""
			(at 0 0 0)
			(layer "F.Fab")
			(effects
				(font
					(size 1.27 1.27)
				)
			)
		)
		(duplicate_pad_numbers_are_jumpers no)
		(fp_line
			(start -9.253728 3.750056)
			(end 9.249918 3.750056)
			(stroke
				(width 0.1524)
				(type default)
			)
			(layer "F.SilkS")
		)
		(fp_line
			(start 0 3.750056)
			(end -9.253728 3.750056)
			(stroke
				(width 0.1524)
				(type default)
			)
			(layer "F.SilkS")
		)
		(fp_circle
			(center 0 3.750056)
			(end 9.249918 3.750056)
			(stroke
				(width 0.1524)
				(type default)
			)
			(fill no)
			(layer "F.SilkS")
		)
		(fp_poly
			(pts
				(arc
					(start 9.249918 3.750056)
					(mid 0 12.999974)
					(end -9.249918 3.750056)
				)
			)
			(stroke
				(width 0)
				(type default)
			)
			(fill yes)
			(layer "F.SilkS")
		)
		(fp_circle
			(center 0 3.750056)
			(end 9.249918 3.750056)
			(stroke
				(width 0.1)
				(type default)
			)
			(fill no)
			(layer "F.Fab")
		)
		(pad "1" thru_hole rect
			(at 0 0)
			(size 1.778 1.778)
			(drill 1.27)
			(layers "*.Cu" "*.Mask")
			(remove_unused_layers no)
			(net "P52V_HS1")
			(clearance 0)
			(padstack
				(mode front_inner_back)
				(layer "Inner"
					(shape circle)
					(size 1.778 1.778)
					(clearance 0)
				)
				(layer "B.Cu"
					(shape rect)
					(size 1.778 1.778)
					(clearance 0)
				)
			)
		)
		(pad "2" thru_hole circle
			(at 0 7.500112)
			(size 1.778 1.778)
			(drill 1.27)
			(layers "*.Cu" "*.Mask")
			(remove_unused_layers no)
			(net "GND")
			(clearance 0)
		)
	)
	(footprint ""
		(layer "F.Cu")
		(at 281.0764 -74.041)
		(property "Reference" "R373"
			(at 0 0 0)
			(layer "F.SilkS")
			(hide yes)
			(effects
				(font
					(size 1.27 1.27)
				)
			)
		)
		(property "Value" ""
			(at 0 0 0)
			(layer "F.Fab")
			(effects
				(font
					(size 1.27 1.27)
				)
			)
		)
		(duplicate_pad_numbers_are_jumpers no)
		(fp_line
			(start -0.7874 -0.4064)
			(end 0.7874 -0.4064)
			(stroke
				(width 0.1524)
				(type default)
			)
			(layer "F.SilkS")
		)
		(fp_line
			(start -0.7874 0.4064)
			(end -0.7874 -0.4064)
			(stroke
				(width 0.1524)
				(type default)
			)
			(layer "F.SilkS")
		)
		(fp_line
			(start 0.7874 -0.4064)
			(end 0.7874 0.4064)
			(stroke
				(width 0.1524)
				(type default)
			)
			(layer "F.SilkS")
		)
		(fp_line
			(start 0.7874 0.4064)
			(end -0.7874 0.4064)
			(stroke
				(width 0.1524)
				(type default)
			)
			(layer "F.SilkS")
		)
		(fp_line
			(start -0.67945 -0.305054)
			(end -0.12065 -0.305054)
			(stroke
				(width 0.1)
				(type default)
			)
			(layer "F.Fab")
		)
		(fp_line
			(start -0.67945 0.3048)
			(end -0.67945 -0.305054)
			(stroke
				(width 0.1)
				(type default)
			)
			(layer "F.Fab")
		)
		(fp_line
			(start -0.12065 -0.305054)
			(end -0.12065 -0.2794)
			(stroke
				(width 0.1)
				(type default)
			)
			(layer "F.Fab")
		)
		(fp_line
			(start -0.12065 -0.2794)
			(end 0.12065 -0.2794)
			(stroke
				(width 0.1)
				(type default)
			)
			(layer "F.Fab")
		)
		(fp_line
			(start -0.12065 0.2794)
			(end -0.12065 0.3048)
			(stroke
				(width 0.1)
				(type default)
			)
			(layer "F.Fab")
		)
		(fp_line
			(start -0.12065 0.3048)
			(end -0.67945 0.3048)
			(stroke
				(width 0.1)
				(type default)
			)
			(layer "F.Fab")
		)
		(fp_line
			(start 0.120396 0.2794)
			(end -0.12065 0.2794)
			(stroke
				(width 0.1)
				(type default)
			)
			(layer "F.Fab")
		)
		(fp_line
			(start 0.120396 0.3048)
			(end 0.120396 0.2794)
			(stroke
				(width 0.1)
				(type default)
			)
			(layer "F.Fab")
		)
		(fp_line
			(start 0.12065 -0.3048)
			(end 0.67945 -0.3048)
			(stroke
				(width 0.1)
				(type default)
			)
			(layer "F.Fab")
		)
		(fp_line
			(start 0.12065 -0.2794)
			(end 0.12065 -0.3048)
			(stroke
				(width 0.1)
				(type default)
			)
			(layer "F.Fab")
		)
		(fp_line
			(start 0.67945 -0.3048)
			(end 0.67945 0.3048)
			(stroke
				(width 0.1)
				(type default)
			)
			(layer "F.Fab")
		)
		(fp_line
			(start 0.67945 0.3048)
			(end 0.120396 0.3048)
			(stroke
				(width 0.1)
				(type default)
			)
			(layer "F.Fab")
		)
		(pad "1" smd circle
			(at -0.40005 0)
			(size 0 0)
			(layers "F.Cu" "F.Mask" "F.Paste")
			(net "P52V_HS1_ADR0")
		)
		(pad "2" smd circle
			(at 0.40005 0)
			(size 0 0)
			(layers "F.Cu" "F.Mask" "F.Paste")
			(net "GND_FIELD_SIGNAL")
		)
	)
	(footprint ""
		(layer "F.Cu")
		(at 444.373 -50.927)
		(property "Reference" "R5900"
			(at 0 0 0)
			(layer "F.SilkS")
			(hide yes)
			(effects
				(font
					(size 1.27 1.27)
				)
			)
		)
		(property "Value" ""
			(at 0 0 0)
			(layer "F.Fab")
			(effects
				(font
					(size 1.27 1.27)
				)
			)
		)
		(duplicate_pad_numbers_are_jumpers no)
		(fp_line
			(start -0.7874 -0.4064)
			(end 0.7874 -0.4064)
			(stroke
				(width 0.1524)
				(type default)
			)
			(layer "F.SilkS")
		)
		(fp_line
			(start -0.7874 0.4064)
			(end -0.7874 -0.4064)
			(stroke
				(width 0.1524)
				(type default)
			)
			(layer "F.SilkS")
		)
		(fp_line
			(start 0.7874 -0.4064)
			(end 0.7874 0.4064)
			(stroke
				(width 0.1524)
				(type default)
			)
			(layer "F.SilkS")
		)
		(fp_line
			(start 0.7874 0.4064)
			(end -0.7874 0.4064)
			(stroke
				(width 0.1524)
				(type default)
			)
			(layer "F.SilkS")
		)
		(fp_line
			(start -0.67945 -0.305054)
			(end -0.12065 -0.305054)
			(stroke
				(width 0.1)
				(type default)
			)
			(layer "F.Fab")
		)
		(fp_line
			(start -0.67945 0.3048)
			(end -0.67945 -0.305054)
			(stroke
				(width 0.1)
				(type default)
			)
			(layer "F.Fab")
		)
		(fp_line
			(start -0.12065 -0.305054)
			(end -0.12065 -0.2794)
			(stroke
				(width 0.1)
				(type default)
			)
			(layer "F.Fab")
		)
		(fp_line
			(start -0.12065 -0.2794)
			(end 0.12065 -0.2794)
			(stroke
				(width 0.1)
				(type default)
			)
			(layer "F.Fab")
		)
		(fp_line
			(start -0.12065 0.2794)
			(end -0.12065 0.3048)
			(stroke
				(width 0.1)
				(type default)
			)
			(layer "F.Fab")
		)
		(fp_line
			(start -0.12065 0.3048)
			(end -0.67945 0.3048)
			(stroke
				(width 0.1)
				(type default)
			)
			(layer "F.Fab")
		)
		(fp_line
			(start 0.120396 0.2794)
			(end -0.12065 0.2794)
			(stroke
				(width 0.1)
				(type default)
			)
			(layer "F.Fab")
		)
		(fp_line
			(start 0.120396 0.3048)
			(end 0.120396 0.2794)
			(stroke
				(width 0.1)
				(type default)
			)
			(layer "F.Fab")
		)
		(fp_line
			(start 0.12065 -0.3048)
			(end 0.67945 -0.3048)
			(stroke
				(width 0.1)
				(type default)
			)
			(layer "F.Fab")
		)
		(fp_line
			(start 0.12065 -0.2794)
			(end 0.12065 -0.3048)
			(stroke
				(width 0.1)
				(type default)
			)
			(layer "F.Fab")
		)
		(fp_line
			(start 0.67945 -0.3048)
			(end 0.67945 0.3048)
			(stroke
				(width 0.1)
				(type default)
			)
			(layer "F.Fab")
		)
		(fp_line
			(start 0.67945 0.3048)
			(end 0.120396 0.3048)
			(stroke
				(width 0.1)
				(type default)
			)
			(layer "F.Fab")
		)
		(pad "1" smd circle
			(at -0.40005 0)
			(size 0 0)
			(layers "F.Cu" "F.Mask" "F.Paste")
			(net "P3V3_HPDB_PG_R")
		)
		(pad "2" smd circle
			(at 0.40005 0)
			(size 0 0)
			(layers "F.Cu" "F.Mask" "F.Paste")
			(net "P3V3_HPDB_PG")
		)
	)
	(footprint ""
		(layer "F.Cu")
		(at 430.276 -47.371 180)
		(property "Reference" "R50"
			(at 0 0 180)
			(layer "F.SilkS")
			(hide yes)
			(effects
				(font
					(size 1.27 1.27)
				)
			)
		)
		(property "Value" ""
			(at 0 0 180)
			(layer "F.Fab")
			(effects
				(font
					(size 1.27 1.27)
				)
			)
		)
		(duplicate_pad_numbers_are_jumpers no)
		(fp_line
			(start 0.7874 0.4064)
			(end -0.7874 0.4064)
			(stroke
				(width 0.1524)
				(type default)
			)
			(layer "F.SilkS")
		)
		(fp_line
			(start 0.7874 -0.4064)
			(end 0.7874 0.4064)
			(stroke
				(width 0.1524)
				(type default)
			)
			(layer "F.SilkS")
		)
		(fp_line
			(start -0.7874 0.4064)
			(end -0.7874 -0.4064)
			(stroke
				(width 0.1524)
				(type default)
			)
			(layer "F.SilkS")
		)
		(fp_line
			(start -0.7874 -0.4064)
			(end 0.7874 -0.4064)
			(stroke
				(width 0.1524)
				(type default)
			)
			(layer "F.SilkS")
		)
		(fp_line
			(start 0.67945 0.3048)
			(end 0.120396 0.3048)
			(stroke
				(width 0.1)
				(type default)
			)
			(layer "F.Fab")
		)
		(fp_line
			(start 0.67945 -0.3048)
			(end 0.67945 0.3048)
			(stroke
				(width 0.1)
				(type default)
			)
			(layer "F.Fab")
		)
		(fp_line
			(start 0.12065 -0.2794)
			(end 0.12065 -0.3048)
			(stroke
				(width 0.1)
				(type default)
			)
			(layer "F.Fab")
		)
		(fp_line
			(start 0.12065 -0.3048)
			(end 0.67945 -0.3048)
			(stroke
				(width 0.1)
				(type default)
			)
			(layer "F.Fab")
		)
		(fp_line
			(start 0.120396 0.3048)
			(end 0.120396 0.2794)
			(stroke
				(width 0.1)
				(type default)
			)
			(layer "F.Fab")
		)
		(fp_line
			(start 0.120396 0.2794)
			(end -0.12065 0.2794)
			(stroke
				(width 0.1)
				(type default)
			)
			(layer "F.Fab")
		)
		(fp_line
			(start -0.12065 0.3048)
			(end -0.67945 0.3048)
			(stroke
				(width 0.1)
				(type default)
			)
			(layer "F.Fab")
		)
		(fp_line
			(start -0.12065 0.2794)
			(end -0.12065 0.3048)
			(stroke
				(width 0.1)
				(type default)
			)
			(layer "F.Fab")
		)
		(fp_line
			(start -0.12065 -0.2794)
			(end 0.12065 -0.2794)
			(stroke
				(width 0.1)
				(type default)
			)
			(layer "F.Fab")
		)
		(fp_line
			(start -0.12065 -0.305054)
			(end -0.12065 -0.2794)
			(stroke
				(width 0.1)
				(type default)
			)
			(layer "F.Fab")
		)
		(fp_line
			(start -0.67945 0.3048)
			(end -0.67945 -0.305054)
			(stroke
				(width 0.1)
				(type default)
			)
			(layer "F.Fab")
		)
		(fp_line
			(start -0.67945 -0.305054)
			(end -0.12065 -0.305054)
			(stroke
				(width 0.1)
				(type default)
			)
			(layer "F.Fab")
		)
		(pad "1" smd circle
			(at -0.40005 0 180)
			(size 0 0)
			(layers "F.Cu" "F.Mask" "F.Paste")
			(net "SMB_PDB_MISC_SCL")
		)
		(pad "2" smd circle
			(at 0.40005 0 180)
			(size 0 0)
			(layers "F.Cu" "F.Mask" "F.Paste")
			(net "SMB_IOEXP_SCL")
		)
	)
)
